(kicad_pcb
	(version 20260206)
	(generator "pcbnew")
	(generator_version "10.0")
	(general
		(thickness 1.6)
		(legacy_teardrops no)
	)
	(paper "A4")
	(title_block
		(title "Bryce Canyon_F.DPB_16315-1-OCP.brd")
		(comment 1 "Bryce Canyon / footprints 809-813 of 2223")
	)
	(layers
		(0 "F.Cu" signal "TOP")
		(4 "In1.Cu" signal "L2GND")
		(6 "In2.Cu" signal "L3")
		(8 "In3.Cu" signal "L4GND")
		(10 "In4.Cu" signal "L5")
		(12 "In5.Cu" signal "L6VCC")
		(14 "In6.Cu" signal "L7VCC")
		(16 "In7.Cu" signal "L8")
		(18 "In8.Cu" signal "L9GND")
		(20 "In9.Cu" signal "L10")
		(22 "In10.Cu" signal "L11GND")
		(2 "B.Cu" signal "BOTTOM")
		(9 "F.Adhes" user "F.Adhesive")
		(11 "B.Adhes" user "B.Adhesive")
		(13 "F.Paste" user "Package Geometry/Pastemask Top")
		(15 "B.Paste" user "Package Geometry/Pastemask Bottom")
		(5 "F.SilkS" user "Ref Des/Silkscreen Top")
		(7 "B.SilkS" user "Ref Des/Silkscreen Bottom")
		(1 "F.Mask" user "Board Geometry/Soldermask Top")
		(3 "B.Mask" user "Board Geometry/Soldermask Bottom")
		(17 "Dwgs.User" user "User.Drawings")
		(19 "Cmts.User" user "User.Comments")
		(21 "Eco1.User" user "User.Eco1")
		(23 "Eco2.User" user "User.Eco2")
		(25 "Edge.Cuts" user "Board Geometry/Outline")
		(27 "Margin" user)
		(31 "F.CrtYd" user "Package Geometry/Place Bound Top")
		(29 "B.CrtYd" user "Package Geometry/Place Bound Bottom")
		(35 "F.Fab" user "Ref Des/Assembly Top")
		(33 "B.Fab" user "Ref Des/Assembly Bottom")
	)
	(footprint ""
		(layer "F.Cu")
		(at 52.234846 -285.285942 180)
		(property "Reference" "Q5"
			(at 0 0 180)
			(layer "F.SilkS")
			(hide yes)
			(effects
				(font
					(size 1.27 1.27)
				)
			)
		)
		(property "Value" "AO4406AL-GP"
			(at -3.707384 -1.5367 180)
			(unlocked yes)
			(layer "F.Fab")
			(hide yes)
			(effects
				(font
					(size 1.016 1.016)
					(thickness 0.1524)
				)
			)
		)
		(property "Device Type" "SOIC8H69"
			(at -3.707384 -3.0607 180)
			(unlocked yes)
			(layer "F.Fab")
			(hide yes)
			(effects
				(font
					(size 1.016 1.016)
					(thickness 0.1524)
				)
			)
		)
		(duplicate_pad_numbers_are_jumpers no)
		(fp_line
			(start 2.1336 1.4224)
			(end 2.1336 -1.4224)
			(stroke
				(width 0.1524)
				(type default)
			)
			(layer "F.SilkS")
		)
		(fp_line
			(start 2.1336 -1.4224)
			(end -2.7432 -1.4224)
			(stroke
				(width 0.1524)
				(type default)
			)
			(layer "F.SilkS")
		)
		(fp_line
			(start -2.1844 -0.0508)
			(end -2.7178 0.508)
			(stroke
				(width 0.1524)
				(type default)
			)
			(layer "F.SilkS")
		)
		(fp_line
			(start -2.6289 3.4417)
			(end -2.6289 1.4732)
			(stroke
				(width 0.381)
				(type default)
			)
			(layer "F.SilkS")
		)
		(fp_line
			(start -2.7178 -0.508)
			(end -2.1844 -0.0508)
			(stroke
				(width 0.1524)
				(type default)
			)
			(layer "F.SilkS")
		)
		(fp_line
			(start -2.7432 1.4224)
			(end 2.1336 1.4224)
			(stroke
				(width 0.1524)
				(type default)
			)
			(layer "F.SilkS")
		)
		(fp_line
			(start -2.7432 1.4224)
			(end -2.6416 1.4224)
			(stroke
				(width 0.1524)
				(type default)
			)
			(layer "F.SilkS")
		)
		(fp_line
			(start -2.7432 -1.4224)
			(end -2.7432 1.4224)
			(stroke
				(width 0.1524)
				(type default)
			)
			(layer "F.SilkS")
		)
		(fp_poly
			(pts
				(xy -2.2098 -1.4224) (xy -2.2098 1.4224) (xy 2.2098 1.4224) (xy 2.2098 -1.4224)
			)
			(stroke
				(width 0)
				(type default)
			)
			(fill yes)
			(layer "F.SilkS")
		)
		(fp_rect
			(start -2.450084 2.999994)
			(end 2.450084 -2.999994)
			(stroke
				(width 0)
				(type default)
			)
			(fill no)
			(layer "F.CrtYd")
		)
		(fp_poly
			(pts
				(xy -2.8194 3.6322) (xy -2.8194 -3.6322) (xy 2.8194 -3.6322) (xy 2.8194 1.18364) (xy 2.450084 1.18364)
				(xy 2.450084 -2.999994) (xy -2.450084 -2.999994) (xy -2.450084 2.999994) (xy 2.450084 2.999994)
				(xy 2.450084 1.18618) (xy 2.8194 1.18618) (xy 2.8194 3.6322)
			)
			(stroke
				(width 0)
				(type default)
			)
			(fill no)
			(layer "F.CrtYd")
		)
		(fp_rect
			(start -2.8194 3.6322)
			(end 2.8194 -3.6322)
			(stroke
				(width 0)
				(type default)
			)
			(fill no)
			(layer "F.Fab")
		)
		(pad "1" smd rect
			(at -1.905 2.54 180)
			(size 0.635 1.651)
			(layers "F.Cu" "F.Mask" "F.Paste")
			(net "P5V_HDD1")
		)
		(pad "2" smd rect
			(at -0.635 2.54 180)
			(size 0.635 1.651)
			(layers "F.Cu" "F.Mask" "F.Paste")
			(net "P5V_HDD1")
		)
		(pad "3" smd rect
			(at 0.635 2.54 180)
			(size 0.635 1.651)
			(layers "F.Cu" "F.Mask" "F.Paste")
			(net "P5V_HDD1")
		)
		(pad "4" smd rect
			(at 1.905 2.54 180)
			(size 0.635 1.651)
			(layers "F.Cu" "F.Mask" "F.Paste")
			(net "SW_HDD_P1")
		)
		(pad "5" smd rect
			(at 1.905 -2.54 180)
			(size 0.635 1.651)
			(layers "F.Cu" "F.Mask" "F.Paste")
			(net "P5V_A_1")
		)
		(pad "6" smd rect
			(at 0.635 -2.54 180)
			(size 0.635 1.651)
			(layers "F.Cu" "F.Mask" "F.Paste")
			(net "P5V_A_1")
		)
		(pad "7" smd rect
			(at -0.635 -2.54 180)
			(size 0.635 1.651)
			(layers "F.Cu" "F.Mask" "F.Paste")
			(net "P5V_A_1")
		)
		(pad "8" smd rect
			(at -1.905 -2.54 180)
			(size 0.635 1.651)
			(layers "F.Cu" "F.Mask" "F.Paste")
			(net "P5V_A_1")
		)
	)
	(footprint ""
		(layer "F.Cu")
		(at 20.430998 -48.554894 180)
		(property "Reference" "Q145"
			(at 0 0 180)
			(layer "F.SilkS")
			(hide yes)
			(effects
				(font
					(size 1.27 1.27)
				)
			)
		)
		(property "Value" "2N7002KDW-GP"
			(at -2.3622 -8.2042 180)
			(unlocked yes)
			(layer "F.Fab")
			(hide yes)
			(effects
				(font
					(size 1.016 1.016)
					(thickness 0.1524)
				)
			)
		)
		(property "Device Type" "SOT-363H44"
			(at -2.3622 -10.1092 180)
			(unlocked yes)
			(layer "F.Fab")
			(hide yes)
			(effects
				(font
					(size 1.016 1.016)
					(thickness 0.1524)
				)
			)
		)
		(duplicate_pad_numbers_are_jumpers no)
		(fp_line
			(start 1.4478 1.7018)
			(end 1.4478 -1.7018)
			(stroke
				(width 0.1524)
				(type default)
			)
			(layer "F.SilkS")
		)
		(fp_line
			(start 1.4478 -1.7018)
			(end -1.4478 -1.7018)
			(stroke
				(width 0.1524)
				(type default)
			)
			(layer "F.SilkS")
		)
		(fp_line
			(start -1.27 1.524)
			(end -1.27 0.6604)
			(stroke
				(width 0.4826)
				(type default)
			)
			(layer "F.SilkS")
		)
		(fp_line
			(start -1.4478 1.7018)
			(end 1.4478 1.7018)
			(stroke
				(width 0.1524)
				(type default)
			)
			(layer "F.SilkS")
		)
		(fp_line
			(start -1.4478 -1.7018)
			(end -1.4478 1.7018)
			(stroke
				(width 0.1524)
				(type default)
			)
			(layer "F.SilkS")
		)
		(fp_poly
			(pts
				(xy -1.524 -1.778) (xy 1.524 -1.778) (xy 1.524 1.778) (xy -1.524 1.778)
			)
			(stroke
				(width 0)
				(type default)
			)
			(fill no)
			(layer "F.CrtYd")
		)
		(fp_poly
			(pts
				(xy -1.524 -1.778) (xy 1.524 -1.778) (xy 1.524 1.778) (xy -1.524 1.778)
			)
			(stroke
				(width 0)
				(type default)
			)
			(fill no)
			(layer "F.Fab")
		)
		(pad "1" smd rect
			(at -0.65024 0.9398 180)
			(size 0.4064 1.016)
			(layers "F.Cu" "F.Mask" "F.Paste")
			(net "GND")
		)
		(pad "2" smd rect
			(at 0 0.9398 180)
			(size 0.4064 1.016)
			(layers "F.Cu" "F.Mask" "F.Paste")
			(net "SW_PWR_R_HDD24")
		)
		(pad "3" smd rect
			(at 0.65024 0.9398 180)
			(size 0.4064 1.016)
			(layers "F.Cu" "F.Mask" "F.Paste")
			(net "SW_HDD_P24")
		)
		(pad "4" smd rect
			(at 0.65024 -0.9398 180)
			(size 0.4064 1.016)
			(layers "F.Cu" "F.Mask" "F.Paste")
			(net "GND")
		)
		(pad "5" smd rect
			(at 0 -0.9398 180)
			(size 0.4064 1.016)
			(layers "F.Cu" "F.Mask" "F.Paste")
			(net "SW_HDD_G24")
		)
		(pad "6" smd rect
			(at -0.65024 -0.9398 180)
			(size 0.4064 1.016)
			(layers "F.Cu" "F.Mask" "F.Paste")
			(net "SW_HDD_R24")
		)
	)
	(footprint ""
		(layer "F.Cu")
		(at 334.899 -282.872942 -90)
		(property "Reference" "Q36"
			(at 0 0 270)
			(layer "F.SilkS")
			(hide yes)
			(effects
				(font
					(size 1.27 1.27)
				)
			)
		)
		(property "Value" "AO4406AL-GP"
			(at -3.707384 -1.5367 270)
			(unlocked yes)
			(layer "F.Fab")
			(hide yes)
			(effects
				(font
					(size 1.016 1.016)
					(thickness 0.1524)
				)
			)
		)
		(property "Device Type" "SOIC8H69"
			(at -3.707384 -3.0607 270)
			(unlocked yes)
			(layer "F.Fab")
			(hide yes)
			(effects
				(font
					(size 1.016 1.016)
					(thickness 0.1524)
				)
			)
		)
		(duplicate_pad_numbers_are_jumpers no)
		(fp_line
			(start -2.6289 3.4417)
			(end -2.6289 1.4732)
			(stroke
				(width 0.381)
				(type default)
			)
			(layer "F.SilkS")
		)
		(fp_line
			(start -2.7432 1.4224)
			(end -2.6416 1.4224)
			(stroke
				(width 0.1524)
				(type default)
			)
			(layer "F.SilkS")
		)
		(fp_line
			(start -2.7432 1.4224)
			(end 2.1336 1.4224)
			(stroke
				(width 0.1524)
				(type default)
			)
			(layer "F.SilkS")
		)
		(fp_line
			(start 2.1336 1.4224)
			(end 2.1336 -1.4224)
			(stroke
				(width 0.1524)
				(type default)
			)
			(layer "F.SilkS")
		)
		(fp_line
			(start -2.1844 -0.0508)
			(end -2.7178 0.508)
			(stroke
				(width 0.1524)
				(type default)
			)
			(layer "F.SilkS")
		)
		(fp_line
			(start -2.7178 -0.508)
			(end -2.1844 -0.0508)
			(stroke
				(width 0.1524)
				(type default)
			)
			(layer "F.SilkS")
		)
		(fp_line
			(start -2.7432 -1.4224)
			(end -2.7432 1.4224)
			(stroke
				(width 0.1524)
				(type default)
			)
			(layer "F.SilkS")
		)
		(fp_line
			(start 2.1336 -1.4224)
			(end -2.7432 -1.4224)
			(stroke
				(width 0.1524)
				(type default)
			)
			(layer "F.SilkS")
		)
		(fp_poly
			(pts
				(xy -2.2098 -1.4224) (xy -2.2098 1.4224) (xy 2.2098 1.4224) (xy 2.2098 -1.4224)
			)
			(stroke
				(width 0)
				(type default)
			)
			(fill yes)
			(layer "F.SilkS")
		)
		(fp_rect
			(start -2.450084 2.999994)
			(end 2.450084 -2.999994)
			(stroke
				(width 0)
				(type default)
			)
			(fill no)
			(layer "F.CrtYd")
		)
		(fp_poly
			(pts
				(xy -2.8194 3.6322) (xy -2.8194 -3.6322) (xy 2.8194 -3.6322) (xy 2.8194 1.18364) (xy 2.450084 1.18364)
				(xy 2.450084 -2.999994) (xy -2.450084 -2.999994) (xy -2.450084 2.999994) (xy 2.450084 2.999994)
				(xy 2.450084 1.18618) (xy 2.8194 1.18618) (xy 2.8194 3.6322)
			)
			(stroke
				(width 0)
				(type default)
			)
			(fill no)
			(layer "F.CrtYd")
		)
		(fp_rect
			(start -2.8194 3.6322)
			(end 2.8194 -3.6322)
			(stroke
				(width 0)
				(type default)
			)
			(fill no)
			(layer "F.Fab")
		)
		(pad "1" smd rect
			(at -1.905 2.54 270)
			(size 0.635 1.651)
			(layers "F.Cu" "F.Mask" "F.Paste")
			(net "P5V_HDD6")
		)
		(pad "2" smd rect
			(at -0.635 2.54 270)
			(size 0.635 1.651)
			(layers "F.Cu" "F.Mask" "F.Paste")
			(net "P5V_HDD6")
		)
		(pad "3" smd rect
			(at 0.635 2.54 270)
			(size 0.635 1.651)
			(layers "F.Cu" "F.Mask" "F.Paste")
			(net "P5V_HDD6")
		)
		(pad "4" smd rect
			(at 1.905 2.54 270)
			(size 0.635 1.651)
			(layers "F.Cu" "F.Mask" "F.Paste")
			(net "SW_HDD_P6")
		)
		(pad "5" smd rect
			(at 1.905 -2.54 270)
			(size 0.635 1.651)
			(layers "F.Cu" "F.Mask" "F.Paste")
			(net "P5V_A_3")
		)
		(pad "6" smd rect
			(at 0.635 -2.54 270)
			(size 0.635 1.651)
			(layers "F.Cu" "F.Mask" "F.Paste")
			(net "P5V_A_3")
		)
		(pad "7" smd rect
			(at -0.635 -2.54 270)
			(size 0.635 1.651)
			(layers "F.Cu" "F.Mask" "F.Paste")
			(net "P5V_A_3")
		)
		(pad "8" smd rect
			(at -1.905 -2.54 270)
			(size 0.635 1.651)
			(layers "F.Cu" "F.Mask" "F.Paste")
			(net "P5V_A_3")
		)
	)
	(footprint ""
		(layer "F.Cu")
		(at 447.99631 -242.819936 180)
		(property "Reference" "Q237"
			(at 0 0 180)
			(layer "F.SilkS")
			(hide yes)
			(effects
				(font
					(size 1.27 1.27)
				)
			)
		)
		(property "Value" "2N7002K-2-GP"
			(at 0.127 -8.9662 180)
			(unlocked yes)
			(layer "F.Fab")
			(hide yes)
			(effects
				(font
					(size 1.016 1.016)
					(thickness 0.1524)
				)
			)
		)
		(property "Device Type" "SOT23DGS2D4H44"
			(at 0.127 -10.4902 180)
			(unlocked yes)
			(layer "F.Fab")
			(hide yes)
			(effects
				(font
					(size 1.016 1.016)
					(thickness 0.1524)
				)
			)
		)
		(duplicate_pad_numbers_are_jumpers no)
		(fp_line
			(start 1.651 1.778)
			(end 1.651 -1.778)
			(stroke
				(width 0.1524)
				(type default)
			)
			(layer "F.SilkS")
		)
		(fp_line
			(start 1.651 -1.778)
			(end -1.651 -1.778)
			(stroke
				(width 0.1524)
				(type default)
			)
			(layer "F.SilkS")
		)
		(fp_line
			(start -1.651 1.778)
			(end 1.651 1.778)
			(stroke
				(width 0.1524)
				(type default)
			)
			(layer "F.SilkS")
		)
		(fp_line
			(start -1.651 -1.778)
			(end -1.651 1.778)
			(stroke
				(width 0.1524)
				(type default)
			)
			(layer "F.SilkS")
		)
		(fp_poly
			(pts
				(xy -1.778 1.8796) (xy -1.778 -1.8796) (xy 1.778 -1.8796) (xy 1.778 1.8796)
			)
			(stroke
				(width 0)
				(type default)
			)
			(fill no)
			(layer "F.CrtYd")
		)
		(fp_poly
			(pts
				(xy -1.778 1.8796) (xy -1.778 -1.8796) (xy 1.778 -1.8796) (xy 1.778 1.8796)
			)
			(stroke
				(width 0)
				(type default)
			)
			(fill no)
			(layer "F.Fab")
		)
		(pad "D" smd custom
			(at 0 -0.9525 180)
			(size 0.1905 0.1905)
			(layers "F.Cu" "F.Mask" "F.Paste")
			(net "FLT_HDD10_N")
			(options
				(clearance outline)
				(anchor circle)
			)
			(primitives
				(gr_poly
					(pts
						(arc
							(start -0.1778 0.5715)
							(mid -0.321484 0.511984)
							(end -0.381 0.3683)
						)
						(arc
							(start -0.381 -0.3683)
							(mid -0.321484 -0.511984)
							(end -0.1778 -0.5715)
						)
						(arc
							(start 0.1778 -0.5715)
							(mid 0.321484 -0.511984)
							(end 0.381 -0.3683)
						)
						(arc
							(start 0.381 0.3683)
							(mid 0.321484 0.511984)
							(end 0.1778 0.5715)
						)
					)
					(width 0)
					(fill yes)
				)
			)
		)
		(pad "G" smd custom
			(at -0.98425 0.9525 180)
			(size 0.1905 0.1905)
			(layers "F.Cu" "F.Mask" "F.Paste")
			(net "DRIVE_A_10_FLT_LED")
			(options
				(clearance outline)
				(anchor circle)
			)
			(primitives
				(gr_poly
					(pts
						(arc
							(start -0.1778 0.5715)
							(mid -0.321484 0.511984)
							(end -0.381 0.3683)
						)
						(arc
							(start -0.381 -0.3683)
							(mid -0.321484 -0.511984)
							(end -0.1778 -0.5715)
						)
						(arc
							(start 0.1778 -0.5715)
							(mid 0.321484 -0.511984)
							(end 0.381 -0.3683)
						)
						(arc
							(start 0.381 0.3683)
							(mid 0.321484 0.511984)
							(end 0.1778 0.5715)
						)
					)
					(width 0)
					(fill yes)
				)
			)
		)
		(pad "S" smd custom
			(at 0.98425 0.9525 180)
			(size 0.1905 0.1905)
			(layers "F.Cu" "F.Mask" "F.Paste")
			(net "GND")
			(options
				(clearance outline)
				(anchor circle)
			)
			(primitives
				(gr_poly
					(pts
						(arc
							(start -0.1778 0.5715)
							(mid -0.321484 0.511984)
							(end -0.381 0.3683)
						)
						(arc
							(start -0.381 -0.3683)
							(mid -0.321484 -0.511984)
							(end -0.1778 -0.5715)
						)
						(arc
							(start 0.1778 -0.5715)
							(mid 0.321484 -0.511984)
							(end 0.381 -0.3683)
						)
						(arc
							(start 0.381 0.3683)
							(mid 0.321484 0.511984)
							(end 0.1778 0.5715)
						)
					)
					(width 0)
					(fill yes)
				)
			)
		)
	)
	(footprint ""
		(layer "F.Cu")
		(at 150.440898 -74.462894 180)
		(property "Reference" "C411"
			(at 0 0 180)
			(layer "F.SilkS")
			(hide yes)
			(effects
				(font
					(size 1.27 1.27)
				)
			)
		)
		(property "Value" "SC1U25V3KX-GP"
			(at 0 -2.8194 180)
			(unlocked yes)
			(layer "F.Fab")
			(hide yes)
			(effects
				(font
					(size 1.016 1.016)
					(thickness 0.1524)
				)
			)
		)
		(property "Device Type" "C603H36"
			(at 0 -4.3434 180)
			(unlocked yes)
			(layer "F.Fab")
			(hide yes)
			(effects
				(font
					(size 1.016 1.016)
					(thickness 0.1524)
				)
			)
		)
		(duplicate_pad_numbers_are_jumpers no)
		(fp_line
			(start 0.508 0)
			(end -0.508 0)
			(stroke
				(width 0.2032)
				(type default)
			)
			(layer "F.SilkS")
		)
		(fp_rect
			(start -0.5842 1.3335)
			(end 0.5842 -1.3335)
			(stroke
				(width 0)
				(type default)
			)
			(fill no)
			(layer "F.CrtYd")
		)
		(fp_rect
			(start -0.5842 1.3335)
			(end 0.5842 -1.3335)
			(stroke
				(width 0)
				(type default)
			)
			(fill no)
			(layer "F.Fab")
		)
		(pad "1" smd custom
			(at 0 -0.762 180)
			(size 0.2159 0.2159)
			(layers "F.Cu" "F.Mask" "F.Paste")
			(net "P12V_HDD28")
			(options
				(clearance outline)
				(anchor circle)
			)
			(primitives
				(gr_poly
					(pts
						(arc
							(start -0.3302 -0.4318)
							(mid -0.402042 -0.402042)
							(end -0.4318 -0.3302)
						)
						(arc
							(start -0.4318 0.3302)
							(mid -0.402042 0.402042)
							(end -0.3302 0.4318)
						)
						(arc
							(start 0.3302 0.4318)
							(mid 0.402042 0.402042)
							(end 0.4318 0.3302)
						)
						(arc
							(start 0.4318 -0.3302)
							(mid 0.402042 -0.402042)
							(end 0.3302 -0.4318)
						)
					)
					(width 0)
					(fill yes)
				)
			)
		)
		(pad "2" smd custom
			(at 0 0.762 180)
			(size 0.2159 0.2159)
			(layers "F.Cu" "F.Mask" "F.Paste")
			(net "GND")
			(options
				(clearance outline)
				(anchor circle)
			)
			(primitives
				(gr_poly
					(pts
						(arc
							(start -0.3302 -0.4318)
							(mid -0.402042 -0.402042)
							(end -0.4318 -0.3302)
						)
						(arc
							(start -0.4318 0.3302)
							(mid -0.402042 0.402042)
							(end -0.3302 0.4318)
						)
						(arc
							(start 0.3302 0.4318)
							(mid 0.402042 0.402042)
							(end 0.4318 0.3302)
						)
						(arc
							(start 0.4318 -0.3302)
							(mid 0.402042 -0.402042)
							(end 0.3302 -0.4318)
						)
					)
					(width 0)
					(fill yes)
				)
			)
		)
	)
)
